(kicad_pcb
	(version 20241229)
	(generator "pcbnew")
	(generator_version "9.0")
	(general
		(thickness 1.6296)
		(legacy_teardrops no)
	)
	(paper "A3")
	(title_block
		(title "Thunderbolt to 10GbE adapter")
		(date "2026-04-21")
		(rev "1.1.0")
		(company "Antmicro Ltd")
		(comment 1 "www.antmicro.com")
		(comment 9 "footprints 648-652 of 703")
	)
	(layers
		(0 "F.Cu" signal)
		(4 "In1.Cu" signal)
		(6 "In2.Cu" signal)
		(8 "In3.Cu" signal)
		(10 "In4.Cu" signal)
		(12 "In5.Cu" signal)
		(14 "In6.Cu" signal)
		(2 "B.Cu" signal)
		(9 "F.Adhes" user "F.Adhesive")
		(11 "B.Adhes" user "B.Adhesive")
		(13 "F.Paste" user)
		(15 "B.Paste" user)
		(5 "F.SilkS" user "F.Silkscreen")
		(7 "B.SilkS" user "B.Silkscreen")
		(1 "F.Mask" user)
		(3 "B.Mask" user)
		(17 "Dwgs.User" user "User.Drawings")
		(19 "Cmts.User" user "User.Comments")
		(21 "Eco1.User" user "User.Eco1")
		(23 "Eco2.User" user "User.Eco2")
		(25 "Edge.Cuts" user)
		(27 "Margin" user)
		(31 "F.CrtYd" user "F.Courtyard")
		(29 "B.CrtYd" user "B.Courtyard")
		(35 "F.Fab" user)
		(33 "B.Fab" user)
	)
	(footprint "antmicro-footprints:R_0402_1005Metric"
		(layer "B.Cu")
		(at 142.5 119.2 180)
		(descr "Resistor SMD 0402")
		(tags "resistor SMD 0402")
		(property "Reference" "R39"
			(at -19.75 7.450001 0)
			(layer "B.SilkS")
			(effects
				(font
					(size 0.7 0.7)
					(thickness 0.15)
				)
				(justify mirror)
			)
		)
		(property "Value" "R_2k2_0402"
			(at -1.011843 -1.772047 0)
			(layer "B.Fab")
			(effects
				(font
					(size 0.7 0.7)
					(thickness 0.15)
				)
				(justify left bottom mirror)
			)
		)
		(property "Datasheet" "https://www.bourns.com/docs/product-datasheets/cr.pdf"
			(at 0 0 0)
			(layer "B.Fab")
			(hide yes)
			(effects
				(font
					(size 1.27 1.27)
					(thickness 0.15)
				)
				(justify mirror)
			)
		)
		(property "Description" "SMD Chip Resistor, 2.2 kohm, ± 1%, 62.5 mW, 0402 [1005 Metric], Thick Film, General Purpose"
			(at 0 0 0)
			(layer "B.Fab")
			(hide yes)
			(effects
				(font
					(size 1.27 1.27)
					(thickness 0.15)
				)
				(justify mirror)
			)
		)
		(property "MPN" "CR0402-FX-2201GLF"
			(at 0 0 180)
			(unlocked yes)
			(layer "B.Fab")
			(hide yes)
			(effects
				(font
					(size 1 1)
					(thickness 0.15)
				)
				(justify mirror)
			)
		)
		(property "Manufacturer" "Bourns"
			(at 0 0 180)
			(unlocked yes)
			(layer "B.Fab")
			(hide yes)
			(effects
				(font
					(size 1 1)
					(thickness 0.15)
				)
				(justify mirror)
			)
		)
		(property "License" "Apache-2.0"
			(at 0 0 180)
			(unlocked yes)
			(layer "B.Fab")
			(hide yes)
			(effects
				(font
					(size 1 1)
					(thickness 0.15)
				)
				(justify mirror)
			)
		)
		(property "Val" "2k2"
			(at 0 0 180)
			(unlocked yes)
			(layer "B.Fab")
			(hide yes)
			(effects
				(font
					(size 1 1)
					(thickness 0.15)
				)
				(justify mirror)
			)
		)
		(property "Tolerance" "1%"
			(at 0 0 180)
			(unlocked yes)
			(layer "B.Fab")
			(hide yes)
			(effects
				(font
					(size 1 1)
					(thickness 0.15)
				)
				(justify mirror)
			)
		)
		(property "Author" "Antmicro"
			(at 0 0 180)
			(unlocked yes)
			(layer "B.Fab")
			(hide yes)
			(effects
				(font
					(size 1 1)
					(thickness 0.15)
				)
				(justify mirror)
			)
		)
		(sheetname "/TB Controller/")
		(sheetfile "tb.kicad_sch")
		(attr smd)
		(fp_rect
			(start -0.925 0.47)
			(end 0.925 -0.47)
			(stroke
				(width 0.05)
				(type default)
			)
			(fill no)
			(layer "B.CrtYd")
		)
		(fp_rect
			(start -0.5 0.25)
			(end 0.5 -0.25)
			(stroke
				(width 0.15)
				(type solid)
			)
			(fill no)
			(layer "B.Fab")
		)
		(fp_text user "Author: Antmicro"
			(at -0.95 -4.169 0)
			(layer "B.Fab")
			(effects
				(font
					(size 0.7 0.7)
					(thickness 0.15)
				)
				(justify left bottom mirror)
			)
		)
		(fp_text user "${REFERENCE}"
			(at -0.95 -3.168 0)
			(layer "B.Fab")
			(effects
				(font
					(size 0.7 0.7)
					(thickness 0.15)
				)
				(justify left bottom mirror)
			)
		)
		(fp_text user "License: Apache-2.0"
			(at -0.95 -5.169 0)
			(layer "B.Fab")
			(effects
				(font
					(size 0.7 0.7)
					(thickness 0.15)
				)
				(justify left bottom mirror)
			)
		)
		(pad "1" smd roundrect
			(at -0.48 0 180)
			(size 0.59 0.64)
			(layers "B.Cu" "B.Mask" "B.Paste")
			(roundrect_rratio 0.25)
			(net 23 "GND")
			(pintype "passive")
		)
		(pad "2" smd roundrect
			(at 0.48 0 180)
			(size 0.59 0.64)
			(layers "B.Cu" "B.Mask" "B.Paste")
			(roundrect_rratio 0.25)
			(net 222 "Net-(U4C-DPSNK1_DDC_DATA)")
			(pintype "passive")
		)
	)
	(footprint "antmicro-footprints:R_0402_1005Metric"
		(layer "B.Cu")
		(at 145.631866 84.260117 180)
		(descr "Resistor SMD 0402")
		(tags "resistor SMD 0402")
		(property "Reference" "R128"
			(at -17.768134 -9.464883 0)
			(layer "B.SilkS")
			(effects
				(font
					(size 0.7 0.7)
					(thickness 0.15)
				)
				(justify mirror)
			)
		)
		(property "Value" "R_100R_0402"
			(at -1.011843 -1.772047 0)
			(layer "B.Fab")
			(effects
				(font
					(size 0.7 0.7)
					(thickness 0.15)
				)
				(justify left bottom mirror)
			)
		)
		(property "Datasheet" "https://www.bourns.com/docs/product-datasheets/cr.pdf"
			(at 0 0 0)
			(layer "B.Fab")
			(hide yes)
			(effects
				(font
					(size 1.27 1.27)
					(thickness 0.15)
				)
				(justify mirror)
			)
		)
		(property "Description" "SMD Chip Resistor, 100 ohm, ± 1%, 62.5 mW, 0402 [1005 Metric], Thick Film, General Purpose"
			(at 0 0 0)
			(layer "B.Fab")
			(hide yes)
			(effects
				(font
					(size 1.27 1.27)
					(thickness 0.15)
				)
				(justify mirror)
			)
		)
		(property "MPN" "CR0402-FX-1000GLF"
			(at 0 0 180)
			(unlocked yes)
			(layer "B.Fab")
			(hide yes)
			(effects
				(font
					(size 1 1)
					(thickness 0.15)
				)
				(justify mirror)
			)
		)
		(property "Manufacturer" "Bourns"
			(at 0 0 180)
			(unlocked yes)
			(layer "B.Fab")
			(hide yes)
			(effects
				(font
					(size 1 1)
					(thickness 0.15)
				)
				(justify mirror)
			)
		)
		(property "License" "Apache-2.0"
			(at 0 0 180)
			(unlocked yes)
			(layer "B.Fab")
			(hide yes)
			(effects
				(font
					(size 1 1)
					(thickness 0.15)
				)
				(justify mirror)
			)
		)
		(property "Author" "Antmicro"
			(at 0 0 180)
			(unlocked yes)
			(layer "B.Fab")
			(hide yes)
			(effects
				(font
					(size 1 1)
					(thickness 0.15)
				)
				(justify mirror)
			)
		)
		(property "Val" "100R"
			(at 0 0 180)
			(unlocked yes)
			(layer "B.Fab")
			(hide yes)
			(effects
				(font
					(size 1 1)
					(thickness 0.15)
				)
				(justify mirror)
			)
		)
		(property "Tolerance" "1%"
			(at 0 0 180)
			(unlocked yes)
			(layer "B.Fab")
			(hide yes)
			(effects
				(font
					(size 1 1)
					(thickness 0.15)
				)
				(justify mirror)
			)
		)
		(sheetname "/X710-AT2 RSVD/")
		(sheetfile "x710-at2-rsvd.kicad_sch")
		(attr smd)
		(fp_rect
			(start -0.925 0.47)
			(end 0.925 -0.47)
			(stroke
				(width 0.05)
				(type default)
			)
			(fill no)
			(layer "B.CrtYd")
		)
		(fp_rect
			(start -0.5 0.25)
			(end 0.5 -0.25)
			(stroke
				(width 0.15)
				(type solid)
			)
			(fill no)
			(layer "B.Fab")
		)
		(fp_text user "License: Apache-2.0"
			(at -0.95 -5.169 0)
			(layer "B.Fab")
			(effects
				(font
					(size 0.7 0.7)
					(thickness 0.15)
				)
				(justify left bottom mirror)
			)
		)
		(fp_text user "Author: Antmicro"
			(at -0.95 -4.169 0)
			(layer "B.Fab")
			(effects
				(font
					(size 0.7 0.7)
					(thickness 0.15)
				)
				(justify left bottom mirror)
			)
		)
		(fp_text user "${REFERENCE}"
			(at -0.95 -3.168 0)
			(layer "B.Fab")
			(effects
				(font
					(size 0.7 0.7)
					(thickness 0.15)
				)
				(justify left bottom mirror)
			)
		)
		(pad "1" smd roundrect
			(at -0.48 0 180)
			(size 0.59 0.64)
			(layers "B.Cu" "B.Mask" "B.Paste")
			(roundrect_rratio 0.25)
			(net 23 "GND")
			(pintype "passive")
		)
		(pad "2" smd roundrect
			(at 0.48 0 180)
			(size 0.59 0.64)
			(layers "B.Cu" "B.Mask" "B.Paste")
			(roundrect_rratio 0.25)
			(net 98 "/X710-AT2 RSVD/RSVDY18_VSS")
			(pintype "passive")
		)
	)
	(footprint "antmicro-footprints:C_Pol_EIA-A"
		(layer "B.Cu")
		(at 146.7 100.5)
		(property "Reference" "C154"
			(at 2.2 -0.4 0)
			(layer "B.SilkS")
			(effects
				(font
					(size 0.7 0.7)
					(thickness 0.15)
				)
				(justify right top mirror)
			)
		)
		(property "Value" "C_Pol_100u_6V_KEMET-T490-A"
			(at 0 -2 0)
			(layer "B.Fab")
			(effects
				(font
					(size 0.7 0.7)
					(thickness 0.15)
				)
				(justify right top mirror)
			)
		)
		(property "Datasheet" "https://www.kemet.com/en/us/capacitors/product/T490A107M006ATE800.html"
			(at 0 0 0)
			(layer "B.Fab")
			(hide yes)
			(effects
				(font
					(size 1.27 1.27)
					(thickness 0.15)
				)
				(justify mirror)
			)
		)
		(property "Description" "Surface Mount Tantalum Capacitor,  Solid SMD 6V 100uF 1206 20% ESR=800mOhms"
			(at 0 0 0)
			(layer "B.Fab")
			(hide yes)
			(effects
				(font
					(size 1.27 1.27)
					(thickness 0.15)
				)
				(justify mirror)
			)
		)
		(property "Val" "100u"
			(at 0 0 0)
			(unlocked yes)
			(layer "B.Fab")
			(hide yes)
			(effects
				(font
					(size 1 1)
					(thickness 0.15)
				)
				(justify mirror)
			)
		)
		(property "MPN" "T490A107M006ATE800"
			(at 0 0 0)
			(unlocked yes)
			(layer "B.Fab")
			(hide yes)
			(effects
				(font
					(size 1 1)
					(thickness 0.15)
				)
				(justify mirror)
			)
		)
		(property "Manufacturer" "KEMET"
			(at 0 0 0)
			(unlocked yes)
			(layer "B.Fab")
			(hide yes)
			(effects
				(font
					(size 1 1)
					(thickness 0.15)
				)
				(justify mirror)
			)
		)
		(property "License" "Apache-2.0"
			(at 0 0 0)
			(unlocked yes)
			(layer "B.Fab")
			(hide yes)
			(effects
				(font
					(size 1 1)
					(thickness 0.15)
				)
				(justify mirror)
			)
		)
		(property "Author" "Antmicro"
			(at 0 0 0)
			(unlocked yes)
			(layer "B.Fab")
			(hide yes)
			(effects
				(font
					(size 1 1)
					(thickness 0.15)
				)
				(justify mirror)
			)
		)
		(property "Voltage" "6V"
			(at 0 0 0)
			(unlocked yes)
			(layer "B.Fab")
			(hide yes)
			(effects
				(font
					(size 1 1)
					(thickness 0.15)
				)
				(justify mirror)
			)
		)
		(property "Dielectric" "template_dielectric"
			(at 0 0 0)
			(unlocked yes)
			(layer "B.Fab")
			(hide yes)
			(effects
				(font
					(size 1 1)
					(thickness 0.15)
				)
				(justify mirror)
			)
		)
		(sheetname "/X710-AT2 power/")
		(sheetfile "x710-at2-power.kicad_sch")
		(attr smd)
		(fp_line
			(start -2.1 1.1)
			(end -1.8 1.1)
			(stroke
				(width 0.12)
				(type solid)
			)
			(layer "B.SilkS")
		)
		(fp_line
			(start -1.95 1.25)
			(end -1.95 0.95)
			(stroke
				(width 0.12)
				(type solid)
			)
			(layer "B.SilkS")
		)
		(fp_line
			(start -1.5 -0.75)
			(end -1.5 -0.85)
			(stroke
				(width 0.12)
				(type solid)
			)
			(layer "B.SilkS")
		)
		(fp_line
			(start -1.5 0.75)
			(end -1.5 0.85)
			(stroke
				(width 0.12)
				(type solid)
			)
			(layer "B.SilkS")
		)
		(fp_line
			(start -1.5 0.85)
			(end 1.5 0.85)
			(stroke
				(width 0.12)
				(type solid)
			)
			(layer "B.SilkS")
		)
		(fp_line
			(start 1.5 -0.85)
			(end -1.5 -0.85)
			(stroke
				(width 0.12)
				(type solid)
			)
			(layer "B.SilkS")
		)
		(fp_line
			(start 1.5 -0.75)
			(end 1.5 -0.85)
			(stroke
				(width 0.12)
				(type solid)
			)
			(layer "B.SilkS")
		)
		(fp_line
			(start 1.5 0.75)
			(end 1.5 0.85)
			(stroke
				(width 0.12)
				(type solid)
			)
			(layer "B.SilkS")
		)
		(fp_line
			(start -2.05 0.85)
			(end -2.05 -0.85)
			(stroke
				(width 0.05)
				(type solid)
			)
			(layer "B.CrtYd")
		)
		(fp_line
			(start -1.7 -1.05)
			(end -1.7 -0.85)
			(stroke
				(width 0.05)
				(type solid)
			)
			(layer "B.CrtYd")
		)
		(fp_line
			(start -1.7 -0.85)
			(end -2.05 -0.85)
			(stroke
				(width 0.05)
				(type solid)
			)
			(layer "B.CrtYd")
		)
		(fp_line
			(start -1.7 0.85)
			(end -2.05 0.85)
			(stroke
				(width 0.05)
				(type solid)
			)
			(layer "B.CrtYd")
		)
		(fp_line
			(start -1.7 0.85)
			(end -1.7 1.05)
			(stroke
				(width 0.05)
				(type solid)
			)
			(layer "B.CrtYd")
		)
		(fp_line
			(start 1.7 -1.05)
			(end -1.7 -1.05)
			(stroke
				(width 0.05)
				(type solid)
			)
			(layer "B.CrtYd")
		)
		(fp_line
			(start 1.7 -1.05)
			(end 1.7 -0.85)
			(stroke
				(width 0.05)
				(type solid)
			)
			(layer "B.CrtYd")
		)
		(fp_line
			(start 1.7 0.85)
			(end 1.7 1.05)
			(stroke
				(width 0.05)
				(type solid)
			)
			(layer "B.CrtYd")
		)
		(fp_line
			(start 1.7 1.05)
			(end -1.7 1.05)
			(stroke
				(width 0.05)
				(type solid)
			)
			(layer "B.CrtYd")
		)
		(fp_line
			(start 2.05 -0.85)
			(end 1.7 -0.85)
			(stroke
				(width 0.05)
				(type solid)
			)
			(layer "B.CrtYd")
		)
		(fp_line
			(start 2.05 0.85)
			(end 1.7 0.85)
			(stroke
				(width 0.05)
				(type solid)
			)
			(layer "B.CrtYd")
		)
		(fp_line
			(start 2.05 0.85)
			(end 2.05 -0.85)
			(stroke
				(width 0.05)
				(type solid)
			)
			(layer "B.CrtYd")
		)
		(fp_rect
			(start -1.601 0.802)
			(end 1.6 -0.8)
			(stroke
				(width 0.1)
				(type solid)
			)
			(fill no)
			(layer "B.Fab")
		)
		(fp_text user "License: Apache-2.0"
			(at -2.1 -5.198 0)
			(layer "B.Fab")
			(effects
				(font
					(size 0.7 0.7)
					(thickness 0.15)
				)
				(justify right top mirror)
			)
		)
		(fp_text user "Author: Antmicro"
			(at -2.1 -6.198 0)
			(layer "B.Fab")
			(effects
				(font
					(size 0.7 0.7)
					(thickness 0.15)
				)
				(justify right top mirror)
			)
		)
		(fp_text user "${REFERENCE}"
			(at -2.1 -4.198 0)
			(layer "B.Fab")
			(effects
				(font
					(size 0.7 0.7)
					(thickness 0.15)
				)
				(justify right top mirror)
			)
		)
		(pad "1" smd roundrect
			(at -1.2 0)
			(size 1.2 1.2)
			(layers "B.Cu" "B.Mask" "B.Paste")
			(roundrect_rratio 0.1)
			(net 6 "DVDD")
			(pintype "passive")
		)
		(pad "2" smd roundrect
			(at 1.2 0)
			(size 1.2 1.2)
			(layers "B.Cu" "B.Mask" "B.Paste")
			(roundrect_rratio 0.1)
			(net 23 "GND")
			(pintype "passive")
		)
	)
	(footprint "antmicro-footprints:R_0402_1005Metric"
		(layer "B.Cu")
		(at 138.449999 117.15)
		(descr "Resistor SMD 0402")
		(tags "resistor SMD 0402")
		(property "Reference" "R44"
			(at 19.525001 -7.450001 180)
			(layer "B.SilkS")
			(effects
				(font
					(size 0.7 0.7)
					(thickness 0.15)
				)
				(justify mirror)
			)
		)
		(property "Value" "R_10k_0402"
			(at -1.011843 -1.772047 180)
			(layer "B.Fab")
			(effects
				(font
					(size 0.7 0.7)
					(thickness 0.15)
				)
				(justify left bottom mirror)
			)
		)
		(property "Datasheet" "https://www.bourns.com/docs/product-datasheets/cr.pdf"
			(at 0 0 180)
			(layer "B.Fab")
			(hide yes)
			(effects
				(font
					(size 1.27 1.27)
					(thickness 0.15)
				)
				(justify mirror)
			)
		)
		(property "Description" "SMD Chip Resistor, 10 kohm, ± 1%, 62.5 mW, 0402 [1005 Metric], Thick Film, General Purpose"
			(at 0 0 180)
			(layer "B.Fab")
			(hide yes)
			(effects
				(font
					(size 1.27 1.27)
					(thickness 0.15)
				)
				(justify mirror)
			)
		)
		(property "MPN" "CR0402-FX-1002GLF"
			(at 0 0 0)
			(unlocked yes)
			(layer "B.Fab")
			(hide yes)
			(effects
				(font
					(size 1 1)
					(thickness 0.15)
				)
				(justify mirror)
			)
		)
		(property "Manufacturer" "Bourns"
			(at 0 0 0)
			(unlocked yes)
			(layer "B.Fab")
			(hide yes)
			(effects
				(font
					(size 1 1)
					(thickness 0.15)
				)
				(justify mirror)
			)
		)
		(property "License" "Apache-2.0"
			(at 0 0 0)
			(unlocked yes)
			(layer "B.Fab")
			(hide yes)
			(effects
				(font
					(size 1 1)
					(thickness 0.15)
				)
				(justify mirror)
			)
		)
		(property "Val" "10k"
			(at 0 0 0)
			(unlocked yes)
			(layer "B.Fab")
			(hide yes)
			(effects
				(font
					(size 1 1)
					(thickness 0.15)
				)
				(justify mirror)
			)
		)
		(property "Tolerance" "1%"
			(at 0 0 0)
			(unlocked yes)
			(layer "B.Fab")
			(hide yes)
			(effects
				(font
					(size 1 1)
					(thickness 0.15)
				)
				(justify mirror)
			)
		)
		(property "Author" "Antmicro"
			(at 0 0 0)
			(unlocked yes)
			(layer "B.Fab")
			(hide yes)
			(effects
				(font
					(size 1 1)
					(thickness 0.15)
				)
				(justify mirror)
			)
		)
		(sheetname "/TB Controller/")
		(sheetfile "tb.kicad_sch")
		(attr smd)
		(fp_rect
			(start -0.925 0.47)
			(end 0.925 -0.47)
			(stroke
				(width 0.05)
				(type default)
			)
			(fill no)
			(layer "B.CrtYd")
		)
		(fp_rect
			(start -0.5 0.25)
			(end 0.5 -0.25)
			(stroke
				(width 0.15)
				(type solid)
			)
			(fill no)
			(layer "B.Fab")
		)
		(fp_text user "${REFERENCE}"
			(at -0.95 -3.168 180)
			(layer "B.Fab")
			(effects
				(font
					(size 0.7 0.7)
					(thickness 0.15)
				)
				(justify left bottom mirror)
			)
		)
		(fp_text user "License: Apache-2.0"
			(at -0.95 -5.169 180)
			(layer "B.Fab")
			(effects
				(font
					(size 0.7 0.7)
					(thickness 0.15)
				)
				(justify left bottom mirror)
			)
		)
		(fp_text user "Author: Antmicro"
			(at -0.95 -4.169 180)
			(layer "B.Fab")
			(effects
				(font
					(size 0.7 0.7)
					(thickness 0.15)
				)
				(justify left bottom mirror)
			)
		)
		(pad "1" smd roundrect
			(at -0.48 0)
			(size 0.59 0.64)
			(layers "B.Cu" "B.Mask" "B.Paste")
			(roundrect_rratio 0.25)
			(net 187 "Net-(U4C-GPIO_4)")
			(pintype "passive")
		)
		(pad "2" smd roundrect
			(at 0.48 0)
			(size 0.59 0.64)
			(layers "B.Cu" "B.Mask" "B.Paste")
			(roundrect_rratio 0.25)
			(net 23 "GND")
			(pintype "passive")
		)
	)
	(footprint "antmicro-footprints:TP_SMD_0.75mm"
		(layer "B.Cu")
		(at 117.25 88 90)
		(property "Reference" "TP3"
			(at 0.5 -0.85 270)
			(layer "B.SilkS")
			(effects
				(font
					(size 0.7 0.7)
					(thickness 0.15)
				)
				(justify left bottom mirror)
			)
		)
		(property "Value" "TP_0.75mm_SMD"
			(at 0 -1.2 270)
			(layer "B.Fab")
			(effects
				(font
					(size 0.7 0.7)
					(thickness 0.15)
				)
				(justify left bottom mirror)
			)
		)
		(property "Description" "SMT test point"
			(at 0 0 270)
			(layer "B.Fab")
			(hide yes)
			(effects
				(font
					(size 1.27 1.27)
					(thickness 0.15)
				)
				(justify mirror)
			)
		)
		(property "License" "Apache-2.0"
			(at 0 0 90)
			(unlocked yes)
			(layer "B.Fab")
			(hide yes)
			(effects
				(font
					(size 1 1)
					(thickness 0.15)
				)
				(justify mirror)
			)
		)
		(property "Manufacturer" ""
			(at 0 0 90)
			(unlocked yes)
			(layer "B.Fab")
			(hide yes)
			(effects
				(font
					(size 1 1)
					(thickness 0.15)
				)
				(justify mirror)
			)
		)
		(property "MPN" ""
			(at 0 0 90)
			(unlocked yes)
			(layer "B.Fab")
			(hide yes)
			(effects
				(font
					(size 1 1)
					(thickness 0.15)
				)
				(justify mirror)
			)
		)
		(property "Author" "Antmicro"
			(at 0 0 90)
			(unlocked yes)
			(layer "B.Fab")
			(hide yes)
			(effects
				(font
					(size 1 1)
					(thickness 0.15)
				)
				(justify mirror)
			)
		)
		(sheetname "/PD and TB DC-DC/")
		(sheetfile "PD_and_TB_DC_DC.kicad_sch")
		(attr exclude_from_pos_files exclude_from_bom)
		(fp_circle
			(center 0 0)
			(end 0.475 0)
			(stroke
				(width 0.05)
				(type default)
			)
			(fill no)
			(layer "B.CrtYd")
		)
		(fp_text user "${REFERENCE}"
			(at -0.4 -2.7 270)
			(layer "B.Fab")
			(effects
				(font
					(size 0.7 0.7)
					(thickness 0.15)
				)
				(justify left bottom mirror)
			)
		)
		(fp_text user "License: Apache-2.0"
			(at -0.4 -5.101 270)
			(layer "B.Fab")
			(effects
				(font
					(size 0.7 0.7)
					(thickness 0.15)
				)
				(justify left bottom mirror)
			)
		)
		(fp_text user "Author: Antmicro"
			(at -0.4 -3.901 270)
			(layer "B.Fab")
			(effects
				(font
					(size 0.7 0.7)
					(thickness 0.15)
				)
				(justify left bottom mirror)
			)
		)
		(pad "1" smd circle
			(at 0 0 90)
			(size 0.75 0.75)
			(layers "B.Cu" "B.Mask")
			(net 57 "+3V3_TB")
			(pinfunction "1")
			(pintype "passive")
		)
	)
)
